(kicad_pcb
	(version 20221018)
	(generator pcbnew)
	(general
    (thickness 1.62)
  )
	(paper "A4")
	(title_block
    (title "ECP5 - Datacenter Secure Control Module (DC-SCM)")
    (date "2024-07-01")
    (rev "1.2.1")
		(comment 9 "footprints 85-91 of 506")
	)
	(layers
    (0 "F.Cu" signal)
    (1 "In1.Cu" power)
    (2 "In2.Cu" signal)
    (3 "In3.Cu" power)
    (4 "In4.Cu" power)
    (5 "In5.Cu" signal)
    (6 "In6.Cu" power)
    (31 "B.Cu" signal)
    (32 "B.Adhes" user "B.Adhesive")
    (33 "F.Adhes" user "F.Adhesive")
    (34 "B.Paste" user)
    (35 "F.Paste" user)
    (36 "B.SilkS" user "B.Silkscreen")
    (37 "F.SilkS" user "F.Silkscreen")
    (38 "B.Mask" user)
    (39 "F.Mask" user)
    (40 "Dwgs.User" user "User.Drawings")
    (41 "Cmts.User" user "User.Comments")
    (42 "Eco1.User" user "User.Eco1")
    (43 "Eco2.User" user "User.Eco2")
    (44 "Edge.Cuts" user)
    (45 "Margin" user)
    (46 "B.CrtYd" user "B.Courtyard")
    (47 "F.CrtYd" user "F.Courtyard")
    (48 "B.Fab" user)
    (49 "F.Fab" user)
  )
	(footprint "antmicro-footprints:SOIC-8_5.3x5.3x2mm_P1.27mm" (layer "F.Cu")
    (at 79.495 134.11)
    (descr "8-Pin SOIC 208-mil")
    (property "Author" "Antmicro")
    (property "License" "Apache-2.0")
    (property "MPN" "W25Q32JVSSIQ")
    (property "Manufacturer" "Winbond")
    (property "Sheetfile" "rot.kicad_sch")
    (property "Sheetname" "RoT")
    (property "ki_description" "Flash Memory, Serial NOR, 32 Mbit, 4M x 8bit, SPI, SOIC, 8 Pins")
    (property "ki_keywords" "FLASH, SPI, MEMORY")
    (attr smd)
    (fp_text reference "U3" (at -0.0015 -3.2) (layer "F.SilkS")
        (effects (font (size 0.7 0.7) (thickness 0.15)) (justify left bottom))
    )
    (fp_text value "W25Q32JVSSIQ" (at 0 3.8) (layer "F.Fab")
        (effects (font (size 0.7 0.7) (thickness 0.15)) (justify left bottom))
    )
    (fp_text user "License: Apache-2.0" (at -4.675 6.938) (layer "F.Fab") hide
        (effects (font (size 0.7 0.7) (thickness 0.15)) (justify left bottom))
    )
    (fp_text user "${REFERENCE}" (at -4.675 4.938) (layer "F.Fab") hide
        (effects (font (size 0.7 0.7) (thickness 0.15)) (justify left bottom))
    )
    (fp_text user "Author: Antmicro" (at -4.675 5.938) (layer "F.Fab") hide
        (effects (font (size 0.7 0.7) (thickness 0.15)) (justify left bottom))
    )
    (fp_line (start -2.8 -2.641) (end -4.4 -2.641)
      (stroke (width 0.15) (type solid)) (layer "F.SilkS"))
    (fp_circle (center -4.85 -1.905) (end -4.8 -1.855)
      (stroke (width 0.15) (type solid)) (fill solid) (layer "F.SilkS"))
    (fp_rect (start 4.675 -3) (end -4.675 3)
      (stroke (width 0.05) (type solid)) (fill none) (layer "F.CrtYd"))
    (fp_line (start -2.641 -2.641) (end 2.64 -2.641)
      (stroke (width 0.15) (type solid)) (layer "F.Fab"))
    (fp_line (start -2.641 -1.371) (end -1.371 -2.641)
      (stroke (width 0.15) (type solid)) (layer "F.Fab"))
    (fp_line (start -2.641 2.64) (end -2.641 -2.641)
      (stroke (width 0.15) (type solid)) (layer "F.Fab"))
    (fp_line (start 2.64 -2.641) (end 2.64 2.64)
      (stroke (width 0.15) (type solid)) (layer "F.Fab"))
    (fp_line (start 2.64 2.64) (end -2.641 2.64)
      (stroke (width 0.15) (type solid)) (layer "F.Fab"))
    (pad "1" smd roundrect (at -3.601 -1.905 90) (size 0.65 1.65) (layers "F.Cu" "F.Paste" "F.Mask") (roundrect_rratio 0.25)
      (net 129 "QSPIB1_CS_N") (pinfunction "~{CS}") (pintype "input"))
    (pad "2" smd roundrect (at -3.601 -0.635 90) (size 0.65 1.65) (layers "F.Cu" "F.Paste" "F.Mask") (roundrect_rratio 0.25)
      (net 126 "QSPIB1_D1") (pinfunction "SO/IO1") (pintype "bidirectional"))
    (pad "3" smd roundrect (at -3.601 0.633 90) (size 0.65 1.65) (layers "F.Cu" "F.Paste" "F.Mask") (roundrect_rratio 0.25)
      (net 127 "QSPIB1_D2") (pinfunction "~{WP}/IO2") (pintype "bidirectional"))
    (pad "4" smd roundrect (at -3.601 1.904 90) (size 0.65 1.65) (layers "F.Cu" "F.Paste" "F.Mask") (roundrect_rratio 0.25)
      (net 1 "GND") (pinfunction "VSS") (pintype "power_in"))
    (pad "5" smd roundrect (at 3.6 1.904 90) (size 0.65 1.65) (layers "F.Cu" "F.Paste" "F.Mask") (roundrect_rratio 0.25)
      (net 125 "QSPIB1_D0") (pinfunction "SI/IO0") (pintype "bidirectional"))
    (pad "6" smd roundrect (at 3.6 0.633 90) (size 0.65 1.65) (layers "F.Cu" "F.Paste" "F.Mask") (roundrect_rratio 0.25)
      (net 124 "QSPIB_CLK") (pinfunction "SCLK") (pintype "input"))
    (pad "7" smd roundrect (at 3.6 -0.635 90) (size 0.65 1.65) (layers "F.Cu" "F.Paste" "F.Mask") (roundrect_rratio 0.25)
      (net 128 "QSPIB1_D3") (pinfunction "~{HOLD}/IO3") (pintype "bidirectional"))
    (pad "8" smd roundrect (at 3.6 -1.905 90) (size 0.65 1.65) (layers "F.Cu" "F.Paste" "F.Mask") (roundrect_rratio 0.25)
      (net 2 "VCC3V3") (pinfunction "VCC") (pintype "power_in"))
  )
	(footprint "antmicro-footprints:SOIC-8_5.3x5.3x2mm_P1.27mm" (layer "F.Cu")
    (at 79.495 143.01)
    (descr "8-Pin SOIC 208-mil")
    (property "Author" "Antmicro")
    (property "License" "Apache-2.0")
    (property "MPN" "W25Q32JVSSIQ")
    (property "Manufacturer" "Winbond")
    (property "Sheetfile" "rot.kicad_sch")
    (property "Sheetname" "RoT")
    (property "ki_description" "Flash Memory, Serial NOR, 32 Mbit, 4M x 8bit, SPI, SOIC, 8 Pins")
    (property "ki_keywords" "FLASH, SPI, MEMORY")
    (attr smd)
    (fp_text reference "U2" (at -0.0015 -3.2) (layer "F.SilkS")
        (effects (font (size 0.7 0.7) (thickness 0.15)) (justify left bottom))
    )
    (fp_text value "W25Q32JVSSIQ" (at 0 3.8) (layer "F.Fab")
        (effects (font (size 0.7 0.7) (thickness 0.15)) (justify left bottom))
    )
    (fp_text user "License: Apache-2.0" (at -4.675 6.938) (layer "F.Fab") hide
        (effects (font (size 0.7 0.7) (thickness 0.15)) (justify left bottom))
    )
    (fp_text user "${REFERENCE}" (at -4.675 4.938) (layer "F.Fab") hide
        (effects (font (size 0.7 0.7) (thickness 0.15)) (justify left bottom))
    )
    (fp_text user "Author: Antmicro" (at -4.675 5.938) (layer "F.Fab") hide
        (effects (font (size 0.7 0.7) (thickness 0.15)) (justify left bottom))
    )
    (fp_line (start -2.8 -2.641) (end -4.4 -2.641)
      (stroke (width 0.15) (type solid)) (layer "F.SilkS"))
    (fp_circle (center -4.85 -1.905) (end -4.8 -1.855)
      (stroke (width 0.15) (type solid)) (fill solid) (layer "F.SilkS"))
    (fp_rect (start 4.675 -3) (end -4.675 3)
      (stroke (width 0.05) (type solid)) (fill none) (layer "F.CrtYd"))
    (fp_line (start -2.641 -2.641) (end 2.64 -2.641)
      (stroke (width 0.15) (type solid)) (layer "F.Fab"))
    (fp_line (start -2.641 -1.371) (end -1.371 -2.641)
      (stroke (width 0.15) (type solid)) (layer "F.Fab"))
    (fp_line (start -2.641 2.64) (end -2.641 -2.641)
      (stroke (width 0.15) (type solid)) (layer "F.Fab"))
    (fp_line (start 2.64 -2.641) (end 2.64 2.64)
      (stroke (width 0.15) (type solid)) (layer "F.Fab"))
    (fp_line (start 2.64 2.64) (end -2.641 2.64)
      (stroke (width 0.15) (type solid)) (layer "F.Fab"))
    (pad "1" smd roundrect (at -3.601 -1.905 90) (size 0.65 1.65) (layers "F.Cu" "F.Paste" "F.Mask") (roundrect_rratio 0.25)
      (net 134 "QSPIB2_CS_N") (pinfunction "~{CS}") (pintype "input"))
    (pad "2" smd roundrect (at -3.601 -0.635 90) (size 0.65 1.65) (layers "F.Cu" "F.Paste" "F.Mask") (roundrect_rratio 0.25)
      (net 131 "QSPIB2_D1") (pinfunction "SO/IO1") (pintype "bidirectional"))
    (pad "3" smd roundrect (at -3.601 0.633 90) (size 0.65 1.65) (layers "F.Cu" "F.Paste" "F.Mask") (roundrect_rratio 0.25)
      (net 132 "QSPIB2_D2") (pinfunction "~{WP}/IO2") (pintype "bidirectional"))
    (pad "4" smd roundrect (at -3.601 1.904 90) (size 0.65 1.65) (layers "F.Cu" "F.Paste" "F.Mask") (roundrect_rratio 0.25)
      (net 1 "GND") (pinfunction "VSS") (pintype "power_in"))
    (pad "5" smd roundrect (at 3.6 1.904 90) (size 0.65 1.65) (layers "F.Cu" "F.Paste" "F.Mask") (roundrect_rratio 0.25)
      (net 130 "QSPIB2_D0") (pinfunction "SI/IO0") (pintype "bidirectional"))
    (pad "6" smd roundrect (at 3.6 0.633 90) (size 0.65 1.65) (layers "F.Cu" "F.Paste" "F.Mask") (roundrect_rratio 0.25)
      (net 124 "QSPIB_CLK") (pinfunction "SCLK") (pintype "input"))
    (pad "7" smd roundrect (at 3.6 -0.635 90) (size 0.65 1.65) (layers "F.Cu" "F.Paste" "F.Mask") (roundrect_rratio 0.25)
      (net 133 "QSPIB2_D3") (pinfunction "~{HOLD}/IO3") (pintype "bidirectional"))
    (pad "8" smd roundrect (at 3.6 -1.905 90) (size 0.65 1.65) (layers "F.Cu" "F.Paste" "F.Mask") (roundrect_rratio 0.25)
      (net 2 "VCC3V3") (pinfunction "VCC") (pintype "power_in"))
  )
	(footprint "antmicro-footprints:R_0402_1005Metric" (layer "F.Cu")
    (at 75.975 165.36 180)
    (descr "Resistor SMD 0402")
    (tags "resistor SMD 0402")
    (property "Author" "Antmicro")
    (property "License" "Apache-2.0")
    (property "MPN" "CR0402-FX-1002GLF")
    (property "Manufacturer" "Bourns")
    (property "Public" "False")
    (property "Sheetfile" "fpga-banks.kicad_sch")
    (property "Sheetname" "FPGA banks")
    (property "Tolerance" "1%")
    (property "Val" "10k")
    (property "ki_description" "SMD Chip Resistor, 10 kohm, ± 1%, 62.5 mW, 0402 [1005 Metric], Thick Film, General Purpose")
    (property "ki_keywords" "0402, SMT, RESISTOR, PASSIVE")
    (attr smd)
    (fp_text reference "R126" (at -2.4 -0.07) (layer "F.SilkS")
        (effects (font (size 0.7 0.7) (thickness 0.127)))
    )
    (fp_text value "R_10k_0402" (at 0 1.17) (layer "F.Fab")
        (effects (font (size 1 1) (thickness 0.15)))
    )
    (fp_text user "Author: Antmicro" (at -0.95 4.169 180) (layer "F.Fab") hide
        (effects (font (size 0.7 0.7) (thickness 0.15)) (justify left bottom))
    )
    (fp_text user "${REFERENCE}" (at 0 0) (layer "F.Fab")
        (effects (font (size 0.25 0.25) (thickness 0.04)))
    )
    (fp_text user "License: Apache-2.0" (at -0.95 5.169 180) (layer "F.Fab") hide
        (effects (font (size 0.7 0.7) (thickness 0.15)) (justify left bottom))
    )
    (fp_rect (start -0.925 -0.47) (end 0.925 0.47)
      (stroke (width 0.05) (type default)) (fill none) (layer "F.CrtYd"))
    (fp_rect (start -0.5 -0.25) (end 0.5 0.25)
      (stroke (width 0.15) (type solid)) (fill none) (layer "F.Fab"))
    (pad "1" smd roundrect (at -0.48 0 180) (size 0.59 0.64) (layers "F.Cu" "F.Paste" "F.Mask") (roundrect_rratio 0.25)
      (net 278 "DONE") (pintype "passive"))
    (pad "2" smd roundrect (at 0.48 0 180) (size 0.59 0.64) (layers "F.Cu" "F.Paste" "F.Mask") (roundrect_rratio 0.25)
      (net 2 "VCC3V3") (pintype "passive"))
  )
	(footprint "antmicro-footprints:R_0402_1005Metric" (layer "F.Cu")
    (at 73.77 161.02 180)
    (descr "Resistor SMD 0402")
    (tags "resistor SMD 0402")
    (property "Author" "Antmicro")
    (property "License" "Apache-2.0")
    (property "MPN" "CR0402-FX-1002GLF")
    (property "Manufacturer" "Bourns")
    (property "Public" "False")
    (property "Sheetfile" "fpga-banks.kicad_sch")
    (property "Sheetname" "FPGA banks")
    (property "Tolerance" "1%")
    (property "Val" "10k")
    (property "ki_description" "SMD Chip Resistor, 10 kohm, ± 1%, 62.5 mW, 0402 [1005 Metric], Thick Film, General Purpose")
    (property "ki_keywords" "0402, SMT, RESISTOR, PASSIVE")
    (attr smd)
    (fp_text reference "R127" (at -0.64 0.96) (layer "F.SilkS")
        (effects (font (size 0.7 0.7) (thickness 0.127)))
    )
    (fp_text value "R_10k_0402" (at 0 1.17) (layer "F.Fab")
        (effects (font (size 1 1) (thickness 0.15)))
    )
    (fp_text user "License: Apache-2.0" (at -0.95 5.169 180) (layer "F.Fab") hide
        (effects (font (size 0.7 0.7) (thickness 0.15)) (justify left bottom))
    )
    (fp_text user "Author: Antmicro" (at -0.95 4.169 180) (layer "F.Fab") hide
        (effects (font (size 0.7 0.7) (thickness 0.15)) (justify left bottom))
    )
    (fp_text user "${REFERENCE}" (at 0 0) (layer "F.Fab")
        (effects (font (size 0.25 0.25) (thickness 0.04)))
    )
    (fp_rect (start -0.925 -0.47) (end 0.925 0.47)
      (stroke (width 0.05) (type default)) (fill none) (layer "F.CrtYd"))
    (fp_rect (start -0.5 -0.25) (end 0.5 0.25)
      (stroke (width 0.15) (type solid)) (fill none) (layer "F.Fab"))
    (pad "1" smd roundrect (at -0.48 0 180) (size 0.59 0.64) (layers "F.Cu" "F.Paste" "F.Mask") (roundrect_rratio 0.25)
      (net 269 "INIT_N") (pintype "passive"))
    (pad "2" smd roundrect (at 0.48 0 180) (size 0.59 0.64) (layers "F.Cu" "F.Paste" "F.Mask") (roundrect_rratio 0.25)
      (net 2 "VCC3V3") (pintype "passive"))
  )
	(footprint "antmicro-footprints:R_0402_1005Metric" (layer "F.Cu")
    (at 75.99 164.16)
    (descr "Resistor SMD 0402")
    (tags "resistor SMD 0402")
    (property "Author" "Antmicro")
    (property "License" "Apache-2.0")
    (property "MPN" "CR0402-FX-22R0GLF")
    (property "Manufacturer" "Bourns")
    (property "Public" "False")
    (property "Sheetfile" "fpga-banks.kicad_sch")
    (property "Sheetname" "FPGA banks")
    (property "Tolerance" "1%")
    (property "Val" "22R")
    (property "ki_description" "SMD Chip Resistor, 22 ohm, ± 1%, 62.5 mW, 0402 [1005 Metric], Thick Film, General Purpose")
    (property "ki_keywords" "0402, SMT, RESISTOR, PASSIVE")
    (attr smd)
    (fp_text reference "R128" (at -0.04 -0.915) (layer "F.SilkS")
        (effects (font (size 0.7 0.7) (thickness 0.127)))
    )
    (fp_text value "R_22R_0402" (at 0 1.17) (layer "F.Fab")
        (effects (font (size 1 1) (thickness 0.15)))
    )
    (fp_text user "Author: Antmicro" (at -0.95 4.169) (layer "F.Fab") hide
        (effects (font (size 0.7 0.7) (thickness 0.15)) (justify left bottom))
    )
    (fp_text user "${REFERENCE}" (at 0 0) (layer "F.Fab")
        (effects (font (size 0.25 0.25) (thickness 0.04)))
    )
    (fp_text user "License: Apache-2.0" (at -0.95 5.169) (layer "F.Fab") hide
        (effects (font (size 0.7 0.7) (thickness 0.15)) (justify left bottom))
    )
    (fp_rect (start -0.925 -0.47) (end 0.925 0.47)
      (stroke (width 0.05) (type default)) (fill none) (layer "F.CrtYd"))
    (fp_rect (start -0.5 -0.25) (end 0.5 0.25)
      (stroke (width 0.15) (type solid)) (fill none) (layer "F.Fab"))
    (pad "1" smd roundrect (at -0.48 0) (size 0.59 0.64) (layers "F.Cu" "F.Paste" "F.Mask") (roundrect_rratio 0.25)
      (net 401 "Net-(Q17-G)") (pintype "passive"))
    (pad "2" smd roundrect (at 0.48 0) (size 0.59 0.64) (layers "F.Cu" "F.Paste" "F.Mask") (roundrect_rratio 0.25)
      (net 278 "DONE") (pintype "passive"))
  )
	(footprint "antmicro-footprints:R_0402_1005Metric" (layer "F.Cu")
    (at 71.78 161.02 180)
    (descr "Resistor SMD 0402")
    (tags "resistor SMD 0402")
    (property "Author" "Antmicro")
    (property "License" "Apache-2.0")
    (property "MPN" "CR0402-FX-1001GLF")
    (property "Manufacturer" "Bourns")
    (property "Public" "False")
    (property "Sheetfile" "fpga-banks.kicad_sch")
    (property "Sheetname" "FPGA banks")
    (property "Tolerance" "1%")
    (property "Val" "1k")
    (property "ki_description" "SMD Chip Resistor, 1 kohm, ± 1%, 63 mW, 0402 [1005 Metric], Thick Film, General Purpose")
    (property "ki_keywords" "0402, SMT, RESISTOR, PASSIVE")
    (attr smd)
    (fp_text reference "R129" (at 0.37 0.96) (layer "F.SilkS")
        (effects (font (size 0.7 0.7) (thickness 0.127)))
    )
    (fp_text value "R_1k_0402" (at 0 1.17) (layer "F.Fab")
        (effects (font (size 1 1) (thickness 0.15)))
    )
    (fp_text user "${REFERENCE}" (at 0 0) (layer "F.Fab")
        (effects (font (size 0.25 0.25) (thickness 0.04)))
    )
    (fp_text user "License: Apache-2.0" (at -0.95 5.169 180) (layer "F.Fab") hide
        (effects (font (size 0.7 0.7) (thickness 0.15)) (justify left bottom))
    )
    (fp_text user "Author: Antmicro" (at -0.95 4.169 180) (layer "F.Fab") hide
        (effects (font (size 0.7 0.7) (thickness 0.15)) (justify left bottom))
    )
    (fp_rect (start -0.925 -0.47) (end 0.925 0.47)
      (stroke (width 0.05) (type default)) (fill none) (layer "F.CrtYd"))
    (fp_rect (start -0.5 -0.25) (end 0.5 0.25)
      (stroke (width 0.15) (type solid)) (fill none) (layer "F.Fab"))
    (pad "1" smd roundrect (at -0.48 0 180) (size 0.59 0.64) (layers "F.Cu" "F.Paste" "F.Mask") (roundrect_rratio 0.25)
      (net 2 "VCC3V3") (pintype "passive"))
    (pad "2" smd roundrect (at 0.48 0 180) (size 0.59 0.64) (layers "F.Cu" "F.Paste" "F.Mask") (roundrect_rratio 0.25)
      (net 348 "Net-(D14-A)") (pintype "passive"))
  )
	(footprint "antmicro-footprints:LED_0603_1608Metric_G" (layer "F.Cu")
    (at 73.31 162.33 180)
    (descr "LED SMD 0603 Green")
    (tags "LED SMD 0603 Green")
    (property "Author" "Antmicro")
    (property "Color" "Green")
    (property "License" "Apache-2.0")
    (property "MPN" "LG L29K-G2J1-24-Z")
    (property "Manufacturer" "OSRAM")
    (property "Sheetfile" "fpga-banks.kicad_sch")
    (property "Sheetname" "FPGA banks")
    (property "ki_description" "LED, Green, SMD, 0603, 20 mA, 1.7 V, 570 nm")
    (property "ki_keywords" "SMT, DIODE, SEMICONDUCTOR, LED")
    (attr smd)
    (fp_text reference "D14" (at -2.3 0.025) (layer "F.SilkS")
        (effects (font (size 0.7 0.7) (thickness 0.127)))
    )
    (fp_text value "LED_G_0603_LG_L29K-G2J1-24-Z" (at 0 1.77) (layer "F.Fab")
        (effects (font (size 1 1) (thickness 0.15)))
    )
    (fp_text user "${REFERENCE}" (at -1.4224 5.999 180) (layer "F.Fab") hide
        (effects (font (size 0.7 0.7) (thickness 0.15)) (justify left bottom))
    )
    (fp_text user "License: Apache-2.0" (at -1.4224 3.599 180) (layer "F.Fab") hide
        (effects (font (size 0.7 0.7) (thickness 0.15)) (justify left bottom))
    )
    (fp_text user "Author: Antmicro" (at -1.4224 4.799 180) (layer "F.Fab") hide
        (effects (font (size 0.7 0.7) (thickness 0.15)) (justify left bottom))
    )
    (fp_line (start -1.18 -0.319) (end -1.18 0.321)
      (stroke (width 0.15) (type solid)) (layer "F.SilkS"))
    (fp_line (start -0.094672 0.001008) (end -0.24 0.001008)
      (stroke (width 0.1) (type solid)) (layer "F.SilkS"))
    (fp_line (start -0.094672 0.001008) (end 0.105328 -0.198992)
      (stroke (width 0.1) (type solid)) (layer "F.SilkS"))
    (fp_line (start -0.094672 0.201008) (end -0.094672 -0.198992)
      (stroke (width 0.1) (type solid)) (layer "F.SilkS"))
    (fp_line (start 0.105328 0.001008) (end 0.24 0.001)
      (stroke (width 0.1) (type solid)) (layer "F.SilkS"))
    (fp_line (start 0.105328 0.201008) (end -0.094672 0.001008)
      (stroke (width 0.1) (type solid)) (layer "F.SilkS"))
    (fp_line (start 0.105328 0.201008) (end 0.105328 -0.198992)
      (stroke (width 0.1) (type solid)) (layer "F.SilkS"))
    (fp_line (start 0.22 -0.35) (end -0.22 -0.35)
      (stroke (width 0.15) (type solid)) (layer "F.SilkS"))
    (fp_line (start 0.22 0.35) (end -0.22 0.35)
      (stroke (width 0.15) (type solid)) (layer "F.SilkS"))
    (fp_rect (start 1.25 0.65) (end -1.25 -0.65)
      (stroke (width 0.05) (type solid)) (fill none) (layer "F.CrtYd"))
    (fp_line (start -0.199 -0.202) (end -0.199 0.1)
      (stroke (width 0.15) (type solid)) (layer "F.Fab"))
    (fp_line (start -0.199 0) (end -0.597 0)
      (stroke (width 0.15) (type solid)) (layer "F.Fab"))
    (fp_line (start -0.199 0.2) (end -0.199 0.1)
      (stroke (width 0.15) (type solid)) (layer "F.Fab"))
    (fp_line (start -0.101 0) (end 0.201 0.2)
      (stroke (width 0.15) (type solid)) (layer "F.Fab"))
    (fp_line (start 0.201 -0.202) (end -0.101 0)
      (stroke (width 0.15) (type solid)) (layer "F.Fab"))
    (fp_line (start 0.201 0) (end 0.201 -0.202)
      (stroke (width 0.15) (type solid)) (layer "F.Fab"))
    (fp_line (start 0.201 0.2) (end 0.201 0)
      (stroke (width 0.15) (type solid)) (layer "F.Fab"))
    (fp_line (start 0.599 0) (end 0.201 0)
      (stroke (width 0.15) (type solid)) (layer "F.Fab"))
    (fp_rect (start 0.848 0.4) (end -0.85 -0.402)
      (stroke (width 0.15) (type solid)) (fill none) (layer "F.Fab"))
    (pad "1" smd roundrect (at -0.7 0) (size 0.8 1) (layers "F.Cu" "F.Paste" "F.Mask") (roundrect_rratio 0.2)
      (net 269 "INIT_N") (pinfunction "C") (pintype "passive"))
    (pad "2" smd roundrect (at 0.7 0) (size 0.8 1) (layers "F.Cu" "F.Paste" "F.Mask") (roundrect_rratio 0.2)
      (net 348 "Net-(D14-A)") (pinfunction "A") (pintype "passive"))
  )
)
